M48
;Layer_Color=9474304
;FILE_FORMAT=2:5
INCH,LZ
;TYPE=PLATED
T3F00S00C0.01968
T5F00S00C0.02362
;TYPE=NON_PLATED
%
G90
G05
T03
G00X0690354Y-010561
M15
G01X0687598
M16
G00X0697244Y-010561
M15
G01X0694488
M16
G00X0697244Y-0072342
M15
G01X0694488
M16
G00X0690354Y-0072342
M15
G01X0687598
M16
T05
G00X0683071Y-010315
M15
G01X0681496
M16
G00X0683071Y-0074803
M15
G01X0681496
M16
M17
M30
